# BASEBOARD_FAB2 (Tioga Pass) — schematic netlist excerpt (pin names and nets, part order shuffled) for the footprints in the layout excerpt that follows; sources: Cadence DE-HDL packaged netlist, KiCad conversion of Wiwynn_Tioga_Pass_MB.brd

R2N23  RES  10.0K 1% CHIP  pkg 0402  page 135 : A = P3V3_STBY ; B = FM_QAT_EN_N
R9P24  RES  12.1K 1% CHIP  pkg 0402  page 199 : A = A_HSC_PWGIN ; B = AGND_HSC
FB3M3  FERRITE  120 FB  pkg SM  page 127 : A = P1V05_PCH_STBY ; B = P1V05_PCH_STBY_VCCA_XTAL

(kicad_pcb
	(version 20260206)
	(generator "pcbnew")
	(generator_version "10.0")
	(general
		(thickness 1.6)
		(legacy_teardrops no)
	)
	(paper "A4")
	(title_block
		(title "Wiwynn_Tioga_Pass_MB.brd")
		(comment 1 "Tioga Pass / footprints 3040-3042 of 4770")
	)
	(layers
		(0 "F.Cu" signal "TOP")
		(4 "In1.Cu" signal "L2GND")
		(6 "In2.Cu" signal "L3")
		(8 "In3.Cu" signal "L4GND")
		(10 "In4.Cu" signal "L5")
		(12 "In5.Cu" signal "L6GND")
		(14 "In6.Cu" signal "L7VCC")
		(16 "In7.Cu" signal "L8VCC")
		(18 "In8.Cu" signal "L9GND")
		(20 "In9.Cu" signal "L10")
		(22 "In10.Cu" signal "L11GND")
		(24 "In11.Cu" signal "L12")
		(26 "In12.Cu" signal "L13GND")
		(2 "B.Cu" signal "BOTTOM")
		(9 "F.Adhes" user "F.Adhesive")
		(11 "B.Adhes" user "B.Adhesive")
		(13 "F.Paste" user "Package Geometry/Pastemask Top")
		(15 "B.Paste" user "Package Geometry/Pastemask Bottom")
		(5 "F.SilkS" user "Ref Des/Silkscreen Top")
		(7 "B.SilkS" user "Ref Des/Silkscreen Bottom")
		(1 "F.Mask" user "Board Geometry/Soldermask Top")
		(3 "B.Mask" user "Board Geometry/Soldermask Bottom")
		(17 "Dwgs.User" user "User.Drawings")
		(19 "Cmts.User" user "User.Comments")
		(21 "Eco1.User" user "User.Eco1")
		(23 "Eco2.User" user "User.Eco2")
		(25 "Edge.Cuts" user "Board Geometry/Outline")
		(27 "Margin" user)
		(31 "F.CrtYd" user "Package Geometry/Place Bound Top")
		(29 "B.CrtYd" user "Package Geometry/Place Bound Bottom")
		(35 "F.Fab" user "Ref Des/Assembly Top")
		(33 "B.Fab" user "Ref Des/Assembly Bottom")
	)
	(footprint ""
		(layer "B.Cu")
		(at 15.77848 -75.35672 90)
		(property "Reference" "R9P24"
			(at 0 0 90)
			(layer "B.SilkS")
			(hide yes)
			(effects
				(font
					(size 1.27 1.27)
				)
				(justify mirror)
			)
		)
		(property "Value" ""
			(at 0 0 90)
			(layer "B.Fab")
			(effects
				(font
					(size 1.27 1.27)
				)
				(justify mirror)
			)
		)
		(duplicate_pad_numbers_are_jumpers no)
		(fp_rect
			(start -0.2794 -0.1016)
			(end 0.2794 0.9906)
			(stroke
				(width 0)
				(type default)
			)
			(fill no)
			(layer "B.CrtYd")
		)
		(fp_line
			(start 0.2794 -0.1016)
			(end 0.2794 0.9906)
			(stroke
				(width 0.1)
				(type default)
			)
			(layer "B.Fab")
		)
		(fp_line
			(start -0.2794 -0.1016)
			(end 0.2794 -0.1016)
			(stroke
				(width 0.1)
				(type default)
			)
			(layer "B.Fab")
		)
		(fp_line
			(start 0.2794 0.9906)
			(end -0.2794 0.9906)
			(stroke
				(width 0.1)
				(type default)
			)
			(layer "B.Fab")
		)
		(fp_line
			(start -0.2794 0.9906)
			(end -0.2794 -0.1016)
			(stroke
				(width 0.1)
				(type default)
			)
			(layer "B.Fab")
		)
		(pad "1" smd rect
			(at 0 0 270)
			(size 0.508 0.508)
			(layers "B.Cu" "B.Mask" "B.Paste")
			(net "A_HSC_PWGIN")
		)
		(pad "2" smd rect
			(at 0 0.889 270)
			(size 0.508 0.508)
			(layers "B.Cu" "B.Mask" "B.Paste")
			(net "AGND_HSC")
		)
		(zone
			(layer "B.Cu")
			(hatch none 0.5)
			(connect_pads
				(clearance 0)
			)
			(min_thickness 0.25)
			(keepout
				(tracks allowed)
				(vias not_allowed)
				(pads allowed)
				(copperpour not_allowed)
				(footprints allowed)
			)
			(placement
				(enabled no)
				(sheetname "")
			)
			(fill
				(thermal_gap 0.5)
				(thermal_bridge_width 0.5)
				(island_removal_mode 0)
			)
			(polygon
				(pts
					(xy 16.03248 -75.10272) (xy 16.41348 -75.10272) (xy 16.41348 -75.61072) (xy 16.03248 -75.61072)
				)
			)
		)
		(zone
			(layer "B.Cu")
			(hatch none 0.5)
			(connect_pads
				(clearance 0)
			)
			(min_thickness 0.25)
			(keepout
				(tracks not_allowed)
				(vias allowed)
				(pads allowed)
				(copperpour not_allowed)
				(footprints allowed)
			)
			(placement
				(enabled no)
				(sheetname "")
			)
			(fill
				(thermal_gap 0.5)
				(thermal_bridge_width 0.5)
				(island_removal_mode 0)
			)
			(polygon
				(pts
					(xy 16.03248 -75.10272) (xy 16.41348 -75.10272) (xy 16.41348 -75.61072) (xy 16.03248 -75.61072)
				)
			)
		)
	)
	(footprint ""
		(layer "B.Cu")
		(at 405.219408 -93.755718 -90)
		(property "Reference" "R2N23"
			(at 0 0 90)
			(layer "B.SilkS")
			(hide yes)
			(effects
				(font
					(size 1.27 1.27)
				)
				(justify mirror)
			)
		)
		(property "Value" ""
			(at 0 0 90)
			(layer "B.Fab")
			(effects
				(font
					(size 1.27 1.27)
				)
				(justify mirror)
			)
		)
		(duplicate_pad_numbers_are_jumpers no)
		(fp_poly
			(pts
				(xy 0.2794 -0.1016) (xy -0.2794 -0.1016) (xy -0.2794 0.9906) (xy 0.2794 0.9906)
			)
			(stroke
				(width 0)
				(type default)
			)
			(fill no)
			(layer "B.CrtYd")
		)
		(fp_line
			(start -0.2794 0.9906)
			(end -0.2794 -0.1016)
			(stroke
				(width 0.1)
				(type default)
			)
			(layer "B.Fab")
		)
		(fp_line
			(start 0.2794 0.9906)
			(end -0.2794 0.9906)
			(stroke
				(width 0.1)
				(type default)
			)
			(layer "B.Fab")
		)
		(fp_line
			(start -0.2794 -0.1016)
			(end 0.2794 -0.1016)
			(stroke
				(width 0.1)
				(type default)
			)
			(layer "B.Fab")
		)
		(fp_line
			(start 0.2794 -0.1016)
			(end 0.2794 0.9906)
			(stroke
				(width 0.1)
				(type default)
			)
			(layer "B.Fab")
		)
		(pad "1" smd rect
			(at 0 0 90)
			(size 0.508 0.508)
			(layers "B.Cu" "B.Mask" "B.Paste")
			(net "P3V3_STBY")
		)
		(pad "2" smd rect
			(at 0 0.889 90)
			(size 0.508 0.508)
			(layers "B.Cu" "B.Mask" "B.Paste")
			(net "FM_QAT_EN_N")
		)
		(zone
			(layer "B.Cu")
			(hatch none 0.5)
			(connect_pads
				(clearance 0)
			)
			(min_thickness 0.25)
			(keepout
				(tracks not_allowed)
				(vias allowed)
				(pads allowed)
				(copperpour not_allowed)
				(footprints allowed)
			)
			(placement
				(enabled no)
				(sheetname "")
			)
			(fill
				(thermal_gap 0.5)
				(thermal_bridge_width 0.5)
				(island_removal_mode 0)
			)
			(polygon
				(pts
					(xy 404.584408 -93.501718) (xy 404.584408 -94.009718) (xy 404.965408 -94.009718) (xy 404.965408 -93.501718)
				)
			)
		)
		(zone
			(layer "B.Cu")
			(hatch none 0.5)
			(connect_pads
				(clearance 0)
			)
			(min_thickness 0.25)
			(keepout
				(tracks allowed)
				(vias not_allowed)
				(pads allowed)
				(copperpour not_allowed)
				(footprints allowed)
			)
			(placement
				(enabled no)
				(sheetname "")
			)
			(fill
				(thermal_gap 0.5)
				(thermal_bridge_width 0.5)
				(island_removal_mode 0)
			)
			(polygon
				(pts
					(xy 404.965408 -93.501718) (xy 404.965408 -94.009718) (xy 404.584408 -94.009718) (xy 404.584408 -93.501718)
				)
			)
		)
	)
	(footprint ""
		(layer "B.Cu")
		(at 380.492 -131.953 -90)
		(property "Reference" "FB3M3"
			(at 0 0 90)
			(layer "B.SilkS")
			(hide yes)
			(effects
				(font
					(size 1.27 1.27)
				)
				(justify mirror)
			)
		)
		(property "Value" ""
			(at 0 0 90)
			(layer "B.Fab")
			(effects
				(font
					(size 1.27 1.27)
				)
				(justify mirror)
			)
		)
		(duplicate_pad_numbers_are_jumpers no)
		(fp_poly
			(pts
				(xy 0.15113 -0.47498) (xy -1.59893 -0.47498) (xy -1.59893 0.47498) (xy 0.15113 0.47498)
			)
			(stroke
				(width 0)
				(type default)
			)
			(fill no)
			(layer "B.CrtYd")
		)
		(fp_line
			(start -1.59893 0.47498)
			(end 0.15113 0.47498)
			(stroke
				(width 0.1)
				(type default)
			)
			(layer "B.Fab")
		)
		(fp_line
			(start 0.15113 0.47498)
			(end 0.15113 -0.47498)
			(stroke
				(width 0.1)
				(type default)
			)
			(layer "B.Fab")
		)
		(fp_line
			(start -1.59893 -0.47498)
			(end -1.59893 0.47498)
			(stroke
				(width 0.1)
				(type default)
			)
			(layer "B.Fab")
		)
		(fp_line
			(start 0.15113 -0.47498)
			(end -1.59893 -0.47498)
			(stroke
				(width 0.1)
				(type default)
			)
			(layer "B.Fab")
		)
		(pad "1" smd rect
			(at 0 0 90)
			(size 0.9398 0.9398)
			(layers "B.Cu" "B.Mask" "B.Paste")
			(net "P1V05_PCH_STBY")
		)
		(pad "2" smd rect
			(at -1.4478 0 90)
			(size 0.9398 0.9398)
			(layers "B.Cu" "B.Mask" "B.Paste")
			(net "P1V05_PCH_STBY_VCCA_XTAL")
		)
		(zone
			(layer "B.Cu")
			(hatch none 0.5)
			(connect_pads
				(clearance 0)
			)
			(min_thickness 0.25)
			(keepout
				(tracks allowed)
				(vias not_allowed)
				(pads allowed)
				(copperpour not_allowed)
				(footprints allowed)
			)
			(placement
				(enabled no)
				(sheetname "")
			)
			(fill
				(thermal_gap 0.5)
				(thermal_bridge_width 0.5)
				(island_removal_mode 0)
			)
			(polygon
				(pts
					(xy 380.0221 -132.4229) (xy 380.9619 -132.4229) (xy 380.9619 -132.9309) (xy 380.0221 -132.9309)
				)
			)
		)
	)
)
